(kicad_pcb
	(version 20260206)
	(generator "pcbnew")
	(generator_version "10.0")
	(general
		(thickness 1.6)
		(legacy_teardrops no)
	)
	(paper "A4")
	(title_block
		(title "03242023_DA0F0TMBIJ0_F0T_Motherboard_J_brd_V01_OCP.brd")
		(comment 1 "Grand Teton / footprint 2856 of 6105 (J2), pads 1-112 of 291")
	)
	(layers
		(0 "F.Cu" signal "TOP")
		(4 "In1.Cu" signal "GND")
		(6 "In2.Cu" signal "IN1")
		(8 "In3.Cu" signal "GND1")
		(10 "In4.Cu" signal "IN2")
		(12 "In5.Cu" signal "GND2")
		(14 "In6.Cu" signal "IN3")
		(16 "In7.Cu" signal "GND3")
		(18 "In8.Cu" signal "VCC")
		(20 "In9.Cu" signal "VCC1")
		(22 "In10.Cu" signal "GND4")
		(24 "In11.Cu" signal "IN4")
		(26 "In12.Cu" signal "GND5")
		(28 "In13.Cu" signal "IN5")
		(30 "In14.Cu" signal "GND6")
		(32 "In15.Cu" signal "IN6")
		(34 "In16.Cu" signal "GND7")
		(2 "B.Cu" signal "BOTTOM")
		(9 "F.Adhes" user "F.Adhesive")
		(11 "B.Adhes" user "B.Adhesive")
		(13 "F.Paste" user "Package Geometry/Pastemask Top")
		(15 "B.Paste" user "Package Geometry/Pastemask Bottom")
		(5 "F.SilkS" user "Ref Des/Silkscreen Top")
		(7 "B.SilkS" user "Ref Des/Silkscreen Bottom")
		(1 "F.Mask" user "Board Geometry/Soldermask Top")
		(3 "B.Mask" user "Board Geometry/Soldermask Bottom")
		(17 "Dwgs.User" user "User.Drawings")
		(19 "Cmts.User" user "User.Comments")
		(21 "Eco1.User" user "User.Eco1")
		(23 "Eco2.User" user "User.Eco2")
		(25 "Edge.Cuts" user "Board Geometry/Outline")
		(27 "Margin" user)
		(31 "F.CrtYd" user "Package Geometry/Place Bound Top")
		(29 "B.CrtYd" user "Package Geometry/Place Bound Bottom")
		(35 "F.Fab" user "Ref Des/Assembly Top")
		(33 "B.Fab" user "Ref Des/Assembly Bottom")
	)
	(footprint ""
		(layer "F.Cu")
		(at 310.937148 -258.091686)
		(property "Reference" "J2"
			(at -3.683 -81.702148 0)
			(unlocked yes)
			(layer "F.SilkS")
			(effects
				(font
					(size 0.7874 0.5842)
					(thickness 0.1524)
				)
				(justify left)
			)
		)
		(property "Value" ""
			(at 0 0 0)
			(layer "F.Fab")
			(effects
				(font
					(size 1.27 1.27)
				)
			)
		)
		(duplicate_pad_numbers_are_jumpers no)
		(pad "1" smd rect
			(at -2.050034 -63.324994 270)
			(size 0.519938 1.4986)
			(layers "F.Cu" "F.Mask" "F.Paste")
			(net "P12V_S3_AUX_CPU0_NVDIMM")
		)
		(pad "2" smd rect
			(at -2.050034 -62.47511 270)
			(size 0.519938 1.4986)
			(layers "F.Cu" "F.Mask" "F.Paste")
			(net "TP_CHA_CPU0_DIMM2_FRU_0")
		)
		(pad "3" smd rect
			(at -2.050034 -61.624972 270)
			(size 0.519938 1.4986)
			(layers "F.Cu" "F.Mask" "F.Paste")
			(net "P3V3_AUX")
		)
		(pad "4" smd rect
			(at -2.050034 -60.775088 270)
			(size 0.519938 1.4986)
			(layers "F.Cu" "F.Mask" "F.Paste")
			(net "I3C_SPD_DDRABCD_CPU0_LVC1_SCL_1")
		)
		(pad "5" smd rect
			(at -2.050034 -59.92495 270)
			(size 0.519938 1.4986)
			(layers "F.Cu" "F.Mask" "F.Paste")
			(net "I3C_SPD_DDRABCD_CPU0_LVC1_SDA")
		)
		(pad "6" smd rect
			(at -2.050034 -59.075066 270)
			(size 0.519938 1.4986)
			(layers "F.Cu" "F.Mask" "F.Paste")
			(net "GND")
		)
		(pad "7" smd rect
			(at -2.050034 -58.224928 270)
			(size 0.519938 1.4986)
			(layers "F.Cu" "F.Mask" "F.Paste")
			(net "M_A_CPU0_SA_DQ<0>")
		)
		(pad "8" smd rect
			(at -2.050034 -57.375044 270)
			(size 0.519938 1.4986)
			(layers "F.Cu" "F.Mask" "F.Paste")
			(net "GND")
		)
		(pad "9" smd rect
			(at -2.050034 -56.524906 270)
			(size 0.519938 1.4986)
			(layers "F.Cu" "F.Mask" "F.Paste")
			(net "M_A_CPU0_SA_DQ<1>")
		)
		(pad "10" smd rect
			(at -2.050034 -55.675022 270)
			(size 0.519938 1.4986)
			(layers "F.Cu" "F.Mask" "F.Paste")
			(net "GND")
		)
		(pad "11" smd rect
			(at -2.050034 -54.824884 270)
			(size 0.519938 1.4986)
			(layers "F.Cu" "F.Mask" "F.Paste")
			(net "M_A_CPU0_SA_DQS_DP<0>")
		)
		(pad "12" smd rect
			(at -2.050034 -53.975 270)
			(size 0.519938 1.4986)
			(layers "F.Cu" "F.Mask" "F.Paste")
			(net "M_A_CPU0_SA_DQS_DN<0>")
		)
		(pad "13" smd rect
			(at -2.050034 -53.125116 270)
			(size 0.519938 1.4986)
			(layers "F.Cu" "F.Mask" "F.Paste")
			(net "GND")
		)
		(pad "14" smd rect
			(at -2.050034 -52.274978 270)
			(size 0.519938 1.4986)
			(layers "F.Cu" "F.Mask" "F.Paste")
			(net "M_A_CPU0_SA_DQ<4>")
		)
		(pad "15" smd rect
			(at -2.050034 -51.425094 270)
			(size 0.519938 1.4986)
			(layers "F.Cu" "F.Mask" "F.Paste")
			(net "GND")
		)
		(pad "16" smd rect
			(at -2.050034 -50.574956 270)
			(size 0.519938 1.4986)
			(layers "F.Cu" "F.Mask" "F.Paste")
			(net "M_A_CPU0_SA_DQ<5>")
		)
		(pad "17" smd rect
			(at -2.050034 -49.725072 270)
			(size 0.519938 1.4986)
			(layers "F.Cu" "F.Mask" "F.Paste")
			(net "GND")
		)
		(pad "18" smd rect
			(at -2.050034 -48.874934 270)
			(size 0.519938 1.4986)
			(layers "F.Cu" "F.Mask" "F.Paste")
			(net "M_A_CPU0_SA_DQ<8>")
		)
		(pad "19" smd rect
			(at -2.050034 -48.02505 270)
			(size 0.519938 1.4986)
			(layers "F.Cu" "F.Mask" "F.Paste")
			(net "GND")
		)
		(pad "20" smd rect
			(at -2.050034 -47.174912 270)
			(size 0.519938 1.4986)
			(layers "F.Cu" "F.Mask" "F.Paste")
			(net "M_A_CPU0_SA_DQ<9>")
		)
		(pad "21" smd rect
			(at -2.050034 -46.325028 270)
			(size 0.519938 1.4986)
			(layers "F.Cu" "F.Mask" "F.Paste")
			(net "GND")
		)
		(pad "22" smd rect
			(at -2.050034 -45.47489 270)
			(size 0.519938 1.4986)
			(layers "F.Cu" "F.Mask" "F.Paste")
			(net "M_A_CPU0_SA_DQS_DP<1>")
		)
		(pad "23" smd rect
			(at -2.050034 -44.625006 270)
			(size 0.519938 1.4986)
			(layers "F.Cu" "F.Mask" "F.Paste")
			(net "M_A_CPU0_SA_DQS_DN<1>")
		)
		(pad "24" smd rect
			(at -2.050034 -43.775122 270)
			(size 0.519938 1.4986)
			(layers "F.Cu" "F.Mask" "F.Paste")
			(net "GND")
		)
		(pad "25" smd rect
			(at -2.050034 -42.924984 270)
			(size 0.519938 1.4986)
			(layers "F.Cu" "F.Mask" "F.Paste")
			(net "M_A_CPU0_SA_DQ<12>")
		)
		(pad "26" smd rect
			(at -2.050034 -42.0751 270)
			(size 0.519938 1.4986)
			(layers "F.Cu" "F.Mask" "F.Paste")
			(net "GND")
		)
		(pad "27" smd rect
			(at -2.050034 -41.224962 270)
			(size 0.519938 1.4986)
			(layers "F.Cu" "F.Mask" "F.Paste")
			(net "M_A_CPU0_SA_DQ<13>")
		)
		(pad "28" smd rect
			(at -2.050034 -40.375078 270)
			(size 0.519938 1.4986)
			(layers "F.Cu" "F.Mask" "F.Paste")
			(net "GND")
		)
		(pad "29" smd rect
			(at -2.050034 -39.52494 270)
			(size 0.519938 1.4986)
			(layers "F.Cu" "F.Mask" "F.Paste")
			(net "M_A_CPU0_SA_DQ<16>")
		)
		(pad "30" smd rect
			(at -2.050034 -38.675056 270)
			(size 0.519938 1.4986)
			(layers "F.Cu" "F.Mask" "F.Paste")
			(net "GND")
		)
		(pad "31" smd rect
			(at -2.050034 -37.824918 270)
			(size 0.519938 1.4986)
			(layers "F.Cu" "F.Mask" "F.Paste")
			(net "M_A_CPU0_SA_DQ<17>")
		)
		(pad "32" smd rect
			(at -2.050034 -36.975034 270)
			(size 0.519938 1.4986)
			(layers "F.Cu" "F.Mask" "F.Paste")
			(net "GND")
		)
		(pad "33" smd rect
			(at -2.050034 -36.124896 270)
			(size 0.519938 1.4986)
			(layers "F.Cu" "F.Mask" "F.Paste")
			(net "M_A_CPU0_SA_DQS_DP<2>")
		)
		(pad "34" smd rect
			(at -2.050034 -35.275012 270)
			(size 0.519938 1.4986)
			(layers "F.Cu" "F.Mask" "F.Paste")
			(net "M_A_CPU0_SA_DQS_DN<2>")
		)
		(pad "35" smd rect
			(at -2.050034 -34.425128 270)
			(size 0.519938 1.4986)
			(layers "F.Cu" "F.Mask" "F.Paste")
			(net "GND")
		)
		(pad "36" smd rect
			(at -2.050034 -33.57499 270)
			(size 0.519938 1.4986)
			(layers "F.Cu" "F.Mask" "F.Paste")
			(net "M_A_CPU0_SA_DQ<20>")
		)
		(pad "37" smd rect
			(at -2.050034 -32.725106 270)
			(size 0.519938 1.4986)
			(layers "F.Cu" "F.Mask" "F.Paste")
			(net "GND")
		)
		(pad "38" smd rect
			(at -2.050034 -31.874968 270)
			(size 0.519938 1.4986)
			(layers "F.Cu" "F.Mask" "F.Paste")
			(net "M_A_CPU0_SA_DQ<21>")
		)
		(pad "39" smd rect
			(at -2.050034 -31.025084 270)
			(size 0.519938 1.4986)
			(layers "F.Cu" "F.Mask" "F.Paste")
			(net "GND")
		)
		(pad "40" smd rect
			(at -2.050034 -30.174946 270)
			(size 0.519938 1.4986)
			(layers "F.Cu" "F.Mask" "F.Paste")
			(net "M_A_CPU0_SA_DQ<24>")
		)
		(pad "41" smd rect
			(at -2.050034 -29.325062 270)
			(size 0.519938 1.4986)
			(layers "F.Cu" "F.Mask" "F.Paste")
			(net "GND")
		)
		(pad "42" smd rect
			(at -2.050034 -28.474924 270)
			(size 0.519938 1.4986)
			(layers "F.Cu" "F.Mask" "F.Paste")
			(net "M_A_CPU0_SA_DQ<25>")
		)
		(pad "43" smd rect
			(at -2.050034 -27.62504 270)
			(size 0.519938 1.4986)
			(layers "F.Cu" "F.Mask" "F.Paste")
			(net "GND")
		)
		(pad "44" smd rect
			(at -2.050034 -26.774902 270)
			(size 0.519938 1.4986)
			(layers "F.Cu" "F.Mask" "F.Paste")
			(net "M_A_CPU0_SA_DQS_DP<3>")
		)
		(pad "45" smd rect
			(at -2.050034 -25.925018 270)
			(size 0.519938 1.4986)
			(layers "F.Cu" "F.Mask" "F.Paste")
			(net "M_A_CPU0_SA_DQS_DN<3>")
		)
		(pad "46" smd rect
			(at -2.050034 -25.07488 270)
			(size 0.519938 1.4986)
			(layers "F.Cu" "F.Mask" "F.Paste")
			(net "GND")
		)
		(pad "47" smd rect
			(at -2.050034 -24.224996 270)
			(size 0.519938 1.4986)
			(layers "F.Cu" "F.Mask" "F.Paste")
			(net "M_A_CPU0_SA_DQ<28>")
		)
		(pad "48" smd rect
			(at -2.050034 -23.375112 270)
			(size 0.519938 1.4986)
			(layers "F.Cu" "F.Mask" "F.Paste")
			(net "GND")
		)
		(pad "49" smd rect
			(at -2.050034 -22.524974 270)
			(size 0.519938 1.4986)
			(layers "F.Cu" "F.Mask" "F.Paste")
			(net "M_A_CPU0_SA_DQ<29>")
		)
		(pad "50" smd rect
			(at -2.050034 -21.67509 270)
			(size 0.519938 1.4986)
			(layers "F.Cu" "F.Mask" "F.Paste")
			(net "GND")
		)
		(pad "51" smd rect
			(at -2.050034 -20.824952 270)
			(size 0.519938 1.4986)
			(layers "F.Cu" "F.Mask" "F.Paste")
			(net "M_A_CPU0_SA_CB<0>")
		)
		(pad "52" smd rect
			(at -2.050034 -19.975068 270)
			(size 0.519938 1.4986)
			(layers "F.Cu" "F.Mask" "F.Paste")
			(net "GND")
		)
		(pad "53" smd rect
			(at -2.050034 -19.12493 270)
			(size 0.519938 1.4986)
			(layers "F.Cu" "F.Mask" "F.Paste")
			(net "M_A_CPU0_SA_CB<1>")
		)
		(pad "54" smd rect
			(at -2.050034 -18.275046 270)
			(size 0.519938 1.4986)
			(layers "F.Cu" "F.Mask" "F.Paste")
			(net "GND")
		)
		(pad "55" smd rect
			(at -2.050034 -17.424908 270)
			(size 0.519938 1.4986)
			(layers "F.Cu" "F.Mask" "F.Paste")
			(net "M_A_CPU0_SA_DQS_DP<4>")
		)
		(pad "56" smd rect
			(at -2.050034 -16.575024 270)
			(size 0.519938 1.4986)
			(layers "F.Cu" "F.Mask" "F.Paste")
			(net "M_A_CPU0_SA_DQS_DN<4>")
		)
		(pad "57" smd rect
			(at -2.050034 -15.724886 270)
			(size 0.519938 1.4986)
			(layers "F.Cu" "F.Mask" "F.Paste")
			(net "GND")
		)
		(pad "58" smd rect
			(at -2.050034 -14.875002 270)
			(size 0.519938 1.4986)
			(layers "F.Cu" "F.Mask" "F.Paste")
			(net "M_A_CPU0_SA_CB<4>")
		)
		(pad "59" smd rect
			(at -2.050034 -14.025118 270)
			(size 0.519938 1.4986)
			(layers "F.Cu" "F.Mask" "F.Paste")
			(net "GND")
		)
		(pad "60" smd rect
			(at -2.050034 -13.17498 270)
			(size 0.519938 1.4986)
			(layers "F.Cu" "F.Mask" "F.Paste")
			(net "M_A_CPU0_SA_CB<5>")
		)
		(pad "61" smd rect
			(at -2.050034 -12.325096 270)
			(size 0.519938 1.4986)
			(layers "F.Cu" "F.Mask" "F.Paste")
			(net "GND")
		)
		(pad "62" smd rect
			(at -2.050034 -11.474958 270)
			(size 0.519938 1.4986)
			(layers "F.Cu" "F.Mask" "F.Paste")
			(net "M_A_CPU0_ALERT_N")
		)
		(pad "63" smd rect
			(at -2.050034 -10.625074 270)
			(size 0.519938 1.4986)
			(layers "F.Cu" "F.Mask" "F.Paste")
			(net "GND")
		)
		(pad "64" smd rect
			(at -2.050034 -9.774936 270)
			(size 0.519938 1.4986)
			(layers "F.Cu" "F.Mask" "F.Paste")
			(net "M_A_CPU0_SA_CS_N<2>")
		)
		(pad "65" smd rect
			(at -2.050034 -8.925052 270)
			(size 0.519938 1.4986)
			(layers "F.Cu" "F.Mask" "F.Paste")
			(net "GND")
		)
		(pad "66" smd rect
			(at -2.050034 -8.074914 270)
			(size 0.519938 1.4986)
			(layers "F.Cu" "F.Mask" "F.Paste")
			(net "M_A_CPU0_SA_CA<0>")
		)
		(pad "67" smd rect
			(at -2.050034 -7.22503 270)
			(size 0.519938 1.4986)
			(layers "F.Cu" "F.Mask" "F.Paste")
			(net "GND")
		)
		(pad "68" smd rect
			(at -2.050034 -6.374892 270)
			(size 0.519938 1.4986)
			(layers "F.Cu" "F.Mask" "F.Paste")
			(net "M_A_CPU0_SA_CA<2>")
		)
		(pad "69" smd rect
			(at -2.050034 -5.525008 270)
			(size 0.519938 1.4986)
			(layers "F.Cu" "F.Mask" "F.Paste")
			(net "GND")
		)
		(pad "70" smd rect
			(at -2.050034 -4.675124 270)
			(size 0.519938 1.4986)
			(layers "F.Cu" "F.Mask" "F.Paste")
			(net "M_A_CPU0_SA_CA<4>")
		)
		(pad "71" smd rect
			(at -2.050034 -3.824986 270)
			(size 0.519938 1.4986)
			(layers "F.Cu" "F.Mask" "F.Paste")
			(net "GND")
		)
		(pad "72" smd rect
			(at -2.050034 -2.975102 270)
			(size 0.519938 1.4986)
			(layers "F.Cu" "F.Mask" "F.Paste")
			(net "M_A_CPU0_SA_CA<6>")
		)
		(pad "73" smd rect
			(at -2.050034 -2.124964 270)
			(size 0.519938 1.4986)
			(layers "F.Cu" "F.Mask" "F.Paste")
			(net "GND")
		)
		(pad "74" smd rect
			(at -2.050034 -1.27508 270)
			(size 0.519938 1.4986)
			(layers "F.Cu" "F.Mask" "F.Paste")
			(net "M_A_CPU0_SA_PAR")
		)
		(pad "75" smd rect
			(at -2.050034 -0.424942 270)
			(size 0.519938 1.4986)
			(layers "F.Cu" "F.Mask" "F.Paste")
			(net "GND")
		)
		(pad "76" smd rect
			(at -2.050034 5.525008 270)
			(size 0.519938 1.4986)
			(layers "F.Cu" "F.Mask" "F.Paste")
			(net "M_A_CPU0_SB_CA<0>")
		)
		(pad "77" smd rect
			(at -2.050034 6.374892 270)
			(size 0.519938 1.4986)
			(layers "F.Cu" "F.Mask" "F.Paste")
			(net "GND")
		)
		(pad "78" smd rect
			(at -2.050034 7.22503 270)
			(size 0.519938 1.4986)
			(layers "F.Cu" "F.Mask" "F.Paste")
			(net "M_A_CPU0_SB_CA<2>")
		)
		(pad "79" smd rect
			(at -2.050034 8.074914 270)
			(size 0.519938 1.4986)
			(layers "F.Cu" "F.Mask" "F.Paste")
			(net "GND")
		)
		(pad "80" smd rect
			(at -2.050034 8.925052 270)
			(size 0.519938 1.4986)
			(layers "F.Cu" "F.Mask" "F.Paste")
			(net "M_A_CPU0_SB_CA<4>")
		)
		(pad "81" smd rect
			(at -2.050034 9.774936 270)
			(size 0.519938 1.4986)
			(layers "F.Cu" "F.Mask" "F.Paste")
			(net "GND")
		)
		(pad "82" smd rect
			(at -2.050034 10.625074 270)
			(size 0.519938 1.4986)
			(layers "F.Cu" "F.Mask" "F.Paste")
			(net "M_A_CPU0_SB_CA<6>")
		)
		(pad "83" smd rect
			(at -2.050034 11.474958 270)
			(size 0.519938 1.4986)
			(layers "F.Cu" "F.Mask" "F.Paste")
			(net "GND")
		)
		(pad "84" smd rect
			(at -2.050034 12.325096 270)
			(size 0.519938 1.4986)
			(layers "F.Cu" "F.Mask" "F.Paste")
			(net "M_A_CPU0_SB_CS_N<2>")
		)
		(pad "85" smd rect
			(at -2.050034 13.17498 270)
			(size 0.519938 1.4986)
			(layers "F.Cu" "F.Mask" "F.Paste")
			(net "GND")
		)
		(pad "86" smd rect
			(at -2.050034 14.025118 270)
			(size 0.519938 1.4986)
			(layers "F.Cu" "F.Mask" "F.Paste")
			(net "M_A_CPU0_SA_RSP<1>")
		)
		(pad "87" smd rect
			(at -2.050034 14.875002 270)
			(size 0.519938 1.4986)
			(layers "F.Cu" "F.Mask" "F.Paste")
			(net "M_A_CPU0_SB_RSP<1>")
		)
		(pad "88" smd rect
			(at -2.050034 15.724886 270)
			(size 0.519938 1.4986)
			(layers "F.Cu" "F.Mask" "F.Paste")
			(net "GND")
		)
		(pad "89" smd rect
			(at -2.050034 16.575024 270)
			(size 0.519938 1.4986)
			(layers "F.Cu" "F.Mask" "F.Paste")
			(net "M_A_CPU0_SB_CB<4>")
		)
		(pad "90" smd rect
			(at -2.050034 17.424908 270)
			(size 0.519938 1.4986)
			(layers "F.Cu" "F.Mask" "F.Paste")
			(net "GND")
		)
		(pad "91" smd rect
			(at -2.050034 18.275046 270)
			(size 0.519938 1.4986)
			(layers "F.Cu" "F.Mask" "F.Paste")
			(net "M_A_CPU0_SB_CB<5>")
		)
		(pad "92" smd rect
			(at -2.050034 19.12493 270)
			(size 0.519938 1.4986)
			(layers "F.Cu" "F.Mask" "F.Paste")
			(net "GND")
		)
		(pad "93" smd rect
			(at -2.050034 19.975068 270)
			(size 0.519938 1.4986)
			(layers "F.Cu" "F.Mask" "F.Paste")
			(net "M_A_CPU0_SB_DQS_DP<9>")
		)
		(pad "94" smd rect
			(at -2.050034 20.824952 270)
			(size 0.519938 1.4986)
			(layers "F.Cu" "F.Mask" "F.Paste")
			(net "M_A_CPU0_SB_DQS_DN<9>")
		)
		(pad "95" smd rect
			(at -2.050034 21.67509 270)
			(size 0.519938 1.4986)
			(layers "F.Cu" "F.Mask" "F.Paste")
			(net "GND")
		)
		(pad "96" smd rect
			(at -2.050034 22.524974 270)
			(size 0.519938 1.4986)
			(layers "F.Cu" "F.Mask" "F.Paste")
			(net "M_A_CPU0_SB_CB<0>")
		)
		(pad "97" smd rect
			(at -2.050034 23.375112 270)
			(size 0.519938 1.4986)
			(layers "F.Cu" "F.Mask" "F.Paste")
			(net "GND")
		)
		(pad "98" smd rect
			(at -2.050034 24.224996 270)
			(size 0.519938 1.4986)
			(layers "F.Cu" "F.Mask" "F.Paste")
			(net "M_A_CPU0_SB_CB<1>")
		)
		(pad "99" smd rect
			(at -2.050034 25.07488 270)
			(size 0.519938 1.4986)
			(layers "F.Cu" "F.Mask" "F.Paste")
			(net "GND")
		)
		(pad "100" smd rect
			(at -2.050034 25.925018 270)
			(size 0.519938 1.4986)
			(layers "F.Cu" "F.Mask" "F.Paste")
			(net "M_A_CPU0_SB_DQ<0>")
		)
		(pad "101" smd rect
			(at -2.050034 26.774902 270)
			(size 0.519938 1.4986)
			(layers "F.Cu" "F.Mask" "F.Paste")
			(net "GND")
		)
		(pad "102" smd rect
			(at -2.050034 27.62504 270)
			(size 0.519938 1.4986)
			(layers "F.Cu" "F.Mask" "F.Paste")
			(net "M_A_CPU0_SB_DQ<1>")
		)
		(pad "103" smd rect
			(at -2.050034 28.474924 270)
			(size 0.519938 1.4986)
			(layers "F.Cu" "F.Mask" "F.Paste")
			(net "GND")
		)
		(pad "104" smd rect
			(at -2.050034 29.325062 270)
			(size 0.519938 1.4986)
			(layers "F.Cu" "F.Mask" "F.Paste")
			(net "M_A_CPU0_SB_DQS_DP<0>")
		)
		(pad "105" smd rect
			(at -2.050034 30.174946 270)
			(size 0.519938 1.4986)
			(layers "F.Cu" "F.Mask" "F.Paste")
			(net "M_A_CPU0_SB_DQS_DN<0>")
		)
		(pad "106" smd rect
			(at -2.050034 31.025084 270)
			(size 0.519938 1.4986)
			(layers "F.Cu" "F.Mask" "F.Paste")
			(net "GND")
		)
		(pad "107" smd rect
			(at -2.050034 31.874968 270)
			(size 0.519938 1.4986)
			(layers "F.Cu" "F.Mask" "F.Paste")
			(net "M_A_CPU0_SB_DQ<4>")
		)
		(pad "108" smd rect
			(at -2.050034 32.725106 270)
			(size 0.519938 1.4986)
			(layers "F.Cu" "F.Mask" "F.Paste")
			(net "GND")
		)
		(pad "109" smd rect
			(at -2.050034 33.57499 270)
			(size 0.519938 1.4986)
			(layers "F.Cu" "F.Mask" "F.Paste")
			(net "M_A_CPU0_SB_DQ<5>")
		)
		(pad "110" smd rect
			(at -2.050034 34.425128 270)
			(size 0.519938 1.4986)
			(layers "F.Cu" "F.Mask" "F.Paste")
			(net "GND")
		)
		(pad "111" smd rect
			(at -2.050034 35.275012 270)
			(size 0.519938 1.4986)
			(layers "F.Cu" "F.Mask" "F.Paste")
			(net "M_A_CPU0_SB_DQ<8>")
		)
		(pad "112" smd rect
			(at -2.050034 36.124896 270)
			(size 0.519938 1.4986)
			(layers "F.Cu" "F.Mask" "F.Paste")
			(net "GND")
		)
	)
)
